(kicad_pcb
	(version 20260206)
	(generator "pcbnew")
	(generator_version "10.0")
	(general
		(thickness 1.6)
		(legacy_teardrops no)
	)
	(paper "A4")
	(title_block
		(title "03242023_DA0F0TMBIJ0_F0T_Motherboard_J_brd_V01_OCP.brd")
		(comment 1 "Grand Teton / footprints 2727-2732 of 6105")
	)
	(layers
		(0 "F.Cu" signal "TOP")
		(4 "In1.Cu" signal "GND")
		(6 "In2.Cu" signal "IN1")
		(8 "In3.Cu" signal "GND1")
		(10 "In4.Cu" signal "IN2")
		(12 "In5.Cu" signal "GND2")
		(14 "In6.Cu" signal "IN3")
		(16 "In7.Cu" signal "GND3")
		(18 "In8.Cu" signal "VCC")
		(20 "In9.Cu" signal "VCC1")
		(22 "In10.Cu" signal "GND4")
		(24 "In11.Cu" signal "IN4")
		(26 "In12.Cu" signal "GND5")
		(28 "In13.Cu" signal "IN5")
		(30 "In14.Cu" signal "GND6")
		(32 "In15.Cu" signal "IN6")
		(34 "In16.Cu" signal "GND7")
		(2 "B.Cu" signal "BOTTOM")
		(9 "F.Adhes" user "F.Adhesive")
		(11 "B.Adhes" user "B.Adhesive")
		(13 "F.Paste" user "Package Geometry/Pastemask Top")
		(15 "B.Paste" user "Package Geometry/Pastemask Bottom")
		(5 "F.SilkS" user "Ref Des/Silkscreen Top")
		(7 "B.SilkS" user "Ref Des/Silkscreen Bottom")
		(1 "F.Mask" user "Board Geometry/Soldermask Top")
		(3 "B.Mask" user "Board Geometry/Soldermask Bottom")
		(17 "Dwgs.User" user "User.Drawings")
		(19 "Cmts.User" user "User.Comments")
		(21 "Eco1.User" user "User.Eco1")
		(23 "Eco2.User" user "User.Eco2")
		(25 "Edge.Cuts" user "Board Geometry/Outline")
		(27 "Margin" user)
		(31 "F.CrtYd" user "Package Geometry/Place Bound Top")
		(29 "B.CrtYd" user "Package Geometry/Place Bound Bottom")
		(35 "F.Fab" user "Ref Des/Assembly Top")
		(33 "B.Fab" user "Ref Des/Assembly Bottom")
	)
	(footprint ""
		(layer "F.Cu")
		(at 104.34193 -241.97691 -90)
		(property "Reference" "C247"
			(at 0 0 270)
			(layer "F.SilkS")
			(hide yes)
			(effects
				(font
					(size 1.27 1.27)
				)
			)
		)
		(property "Value" ""
			(at 0 0 270)
			(layer "F.Fab")
			(effects
				(font
					(size 1.27 1.27)
				)
			)
		)
		(duplicate_pad_numbers_are_jumpers no)
		(fp_line
			(start -0.7874 0.4064)
			(end -0.7874 -0.4064)
			(stroke
				(width 0.1524)
				(type default)
			)
			(layer "F.SilkS")
		)
		(fp_line
			(start 0.7874 0.4064)
			(end -0.7874 0.4064)
			(stroke
				(width 0.1524)
				(type default)
			)
			(layer "F.SilkS")
		)
		(fp_line
			(start -0.7874 -0.4064)
			(end 0.7874 -0.4064)
			(stroke
				(width 0.1524)
				(type default)
			)
			(layer "F.SilkS")
		)
		(fp_line
			(start 0.7874 -0.4064)
			(end 0.7874 0.4064)
			(stroke
				(width 0.1524)
				(type default)
			)
			(layer "F.SilkS")
		)
		(fp_line
			(start -0.67945 0.3048)
			(end -0.67945 -0.305054)
			(stroke
				(width 0.1)
				(type default)
			)
			(layer "F.Fab")
		)
		(fp_line
			(start -0.12065 0.3048)
			(end -0.67945 0.3048)
			(stroke
				(width 0.1)
				(type default)
			)
			(layer "F.Fab")
		)
		(fp_line
			(start 0.120396 0.3048)
			(end 0.120396 0.2794)
			(stroke
				(width 0.1)
				(type default)
			)
			(layer "F.Fab")
		)
		(fp_line
			(start 0.67945 0.3048)
			(end 0.120396 0.3048)
			(stroke
				(width 0.1)
				(type default)
			)
			(layer "F.Fab")
		)
		(fp_line
			(start -0.12065 0.2794)
			(end -0.12065 0.3048)
			(stroke
				(width 0.1)
				(type default)
			)
			(layer "F.Fab")
		)
		(fp_line
			(start 0.120396 0.2794)
			(end -0.12065 0.2794)
			(stroke
				(width 0.1)
				(type default)
			)
			(layer "F.Fab")
		)
		(fp_line
			(start -0.12065 -0.2794)
			(end 0.12065 -0.2794)
			(stroke
				(width 0.1)
				(type default)
			)
			(layer "F.Fab")
		)
		(fp_line
			(start 0.12065 -0.2794)
			(end 0.12065 -0.3048)
			(stroke
				(width 0.1)
				(type default)
			)
			(layer "F.Fab")
		)
		(fp_line
			(start 0.12065 -0.3048)
			(end 0.67945 -0.3048)
			(stroke
				(width 0.1)
				(type default)
			)
			(layer "F.Fab")
		)
		(fp_line
			(start 0.67945 -0.3048)
			(end 0.67945 0.3048)
			(stroke
				(width 0.1)
				(type default)
			)
			(layer "F.Fab")
		)
		(fp_line
			(start -0.67945 -0.305054)
			(end -0.12065 -0.305054)
			(stroke
				(width 0.1)
				(type default)
			)
			(layer "F.Fab")
		)
		(fp_line
			(start -0.12065 -0.305054)
			(end -0.12065 -0.2794)
			(stroke
				(width 0.1)
				(type default)
			)
			(layer "F.Fab")
		)
		(pad "1" smd circle
			(at -0.40005 0 270)
			(size 0 0)
			(layers "F.Cu" "F.Mask" "F.Paste")
			(net "PVCCIN_CPU1")
		)
		(pad "2" smd circle
			(at 0.40005 0 270)
			(size 0 0)
			(layers "F.Cu" "F.Mask" "F.Paste")
			(net "GND")
		)
	)
	(footprint ""
		(layer "F.Cu")
		(at 208.49336 -120.1166 180)
		(property "Reference" "R4718"
			(at 0 0 180)
			(layer "F.SilkS")
			(hide yes)
			(effects
				(font
					(size 1.27 1.27)
				)
			)
		)
		(property "Value" ""
			(at 0 0 180)
			(layer "F.Fab")
			(effects
				(font
					(size 1.27 1.27)
				)
			)
		)
		(duplicate_pad_numbers_are_jumpers no)
		(fp_line
			(start 0.7874 0.4064)
			(end -0.7874 0.4064)
			(stroke
				(width 0.1524)
				(type default)
			)
			(layer "F.SilkS")
		)
		(fp_line
			(start 0.7874 -0.4064)
			(end 0.7874 0.4064)
			(stroke
				(width 0.1524)
				(type default)
			)
			(layer "F.SilkS")
		)
		(fp_line
			(start -0.7874 0.4064)
			(end -0.7874 -0.4064)
			(stroke
				(width 0.1524)
				(type default)
			)
			(layer "F.SilkS")
		)
		(fp_line
			(start -0.7874 -0.4064)
			(end 0.7874 -0.4064)
			(stroke
				(width 0.1524)
				(type default)
			)
			(layer "F.SilkS")
		)
		(fp_line
			(start 0.67945 0.3048)
			(end 0.120396 0.3048)
			(stroke
				(width 0.1)
				(type default)
			)
			(layer "F.Fab")
		)
		(fp_line
			(start 0.67945 -0.3048)
			(end 0.67945 0.3048)
			(stroke
				(width 0.1)
				(type default)
			)
			(layer "F.Fab")
		)
		(fp_line
			(start 0.12065 -0.2794)
			(end 0.12065 -0.3048)
			(stroke
				(width 0.1)
				(type default)
			)
			(layer "F.Fab")
		)
		(fp_line
			(start 0.12065 -0.3048)
			(end 0.67945 -0.3048)
			(stroke
				(width 0.1)
				(type default)
			)
			(layer "F.Fab")
		)
		(fp_line
			(start 0.120396 0.3048)
			(end 0.120396 0.2794)
			(stroke
				(width 0.1)
				(type default)
			)
			(layer "F.Fab")
		)
		(fp_line
			(start 0.120396 0.2794)
			(end -0.12065 0.2794)
			(stroke
				(width 0.1)
				(type default)
			)
			(layer "F.Fab")
		)
		(fp_line
			(start -0.12065 0.3048)
			(end -0.67945 0.3048)
			(stroke
				(width 0.1)
				(type default)
			)
			(layer "F.Fab")
		)
		(fp_line
			(start -0.12065 0.2794)
			(end -0.12065 0.3048)
			(stroke
				(width 0.1)
				(type default)
			)
			(layer "F.Fab")
		)
		(fp_line
			(start -0.12065 -0.2794)
			(end 0.12065 -0.2794)
			(stroke
				(width 0.1)
				(type default)
			)
			(layer "F.Fab")
		)
		(fp_line
			(start -0.12065 -0.305054)
			(end -0.12065 -0.2794)
			(stroke
				(width 0.1)
				(type default)
			)
			(layer "F.Fab")
		)
		(fp_line
			(start -0.67945 0.3048)
			(end -0.67945 -0.305054)
			(stroke
				(width 0.1)
				(type default)
			)
			(layer "F.Fab")
		)
		(fp_line
			(start -0.67945 -0.305054)
			(end -0.12065 -0.305054)
			(stroke
				(width 0.1)
				(type default)
			)
			(layer "F.Fab")
		)
		(pad "1" smd circle
			(at -0.40005 0 180)
			(size 0 0)
			(layers "F.Cu" "F.Mask" "F.Paste")
			(net "FM_AC_PWR_BTN_PLD_ISO_R_N")
		)
		(pad "2" smd circle
			(at 0.40005 0 180)
			(size 0 0)
			(layers "F.Cu" "F.Mask" "F.Paste")
			(net "FM_AC_PWR_BTN_PLD_ISO_N")
		)
	)
	(footprint ""
		(layer "F.Cu")
		(at 257.85953 -56.495442)
		(property "Reference" "R3955"
			(at 0 0 0)
			(layer "F.SilkS")
			(hide yes)
			(effects
				(font
					(size 1.27 1.27)
				)
			)
		)
		(property "Value" ""
			(at 0 0 0)
			(layer "F.Fab")
			(effects
				(font
					(size 1.27 1.27)
				)
			)
		)
		(duplicate_pad_numbers_are_jumpers no)
		(fp_line
			(start -0.7874 -0.4064)
			(end 0.7874 -0.4064)
			(stroke
				(width 0.1524)
				(type default)
			)
			(layer "F.SilkS")
		)
		(fp_line
			(start -0.7874 0.4064)
			(end -0.7874 -0.4064)
			(stroke
				(width 0.1524)
				(type default)
			)
			(layer "F.SilkS")
		)
		(fp_line
			(start 0.7874 -0.4064)
			(end 0.7874 0.4064)
			(stroke
				(width 0.1524)
				(type default)
			)
			(layer "F.SilkS")
		)
		(fp_line
			(start 0.7874 0.4064)
			(end -0.7874 0.4064)
			(stroke
				(width 0.1524)
				(type default)
			)
			(layer "F.SilkS")
		)
		(fp_line
			(start -0.67945 -0.305054)
			(end -0.12065 -0.305054)
			(stroke
				(width 0.1)
				(type default)
			)
			(layer "F.Fab")
		)
		(fp_line
			(start -0.67945 0.3048)
			(end -0.67945 -0.305054)
			(stroke
				(width 0.1)
				(type default)
			)
			(layer "F.Fab")
		)
		(fp_line
			(start -0.12065 -0.305054)
			(end -0.12065 -0.2794)
			(stroke
				(width 0.1)
				(type default)
			)
			(layer "F.Fab")
		)
		(fp_line
			(start -0.12065 -0.2794)
			(end 0.12065 -0.2794)
			(stroke
				(width 0.1)
				(type default)
			)
			(layer "F.Fab")
		)
		(fp_line
			(start -0.12065 0.2794)
			(end -0.12065 0.3048)
			(stroke
				(width 0.1)
				(type default)
			)
			(layer "F.Fab")
		)
		(fp_line
			(start -0.12065 0.3048)
			(end -0.67945 0.3048)
			(stroke
				(width 0.1)
				(type default)
			)
			(layer "F.Fab")
		)
		(fp_line
			(start 0.120396 0.2794)
			(end -0.12065 0.2794)
			(stroke
				(width 0.1)
				(type default)
			)
			(layer "F.Fab")
		)
		(fp_line
			(start 0.120396 0.3048)
			(end 0.120396 0.2794)
			(stroke
				(width 0.1)
				(type default)
			)
			(layer "F.Fab")
		)
		(fp_line
			(start 0.12065 -0.3048)
			(end 0.67945 -0.3048)
			(stroke
				(width 0.1)
				(type default)
			)
			(layer "F.Fab")
		)
		(fp_line
			(start 0.12065 -0.2794)
			(end 0.12065 -0.3048)
			(stroke
				(width 0.1)
				(type default)
			)
			(layer "F.Fab")
		)
		(fp_line
			(start 0.67945 -0.3048)
			(end 0.67945 0.3048)
			(stroke
				(width 0.1)
				(type default)
			)
			(layer "F.Fab")
		)
		(fp_line
			(start 0.67945 0.3048)
			(end 0.120396 0.3048)
			(stroke
				(width 0.1)
				(type default)
			)
			(layer "F.Fab")
		)
		(pad "1" smd circle
			(at -0.40005 0)
			(size 0 0)
			(layers "F.Cu" "F.Mask" "F.Paste")
			(net "P12V_E1S_IMON_0")
		)
		(pad "2" smd circle
			(at 0.40005 0)
			(size 0 0)
			(layers "F.Cu" "F.Mask" "F.Paste")
			(net "P12V_E1S_0_ISENSE_MPS_MAM")
		)
	)
	(footprint ""
		(layer "F.Cu")
		(at 120.36044 -428.107348)
		(property "Reference" "R3507"
			(at 0 0 0)
			(layer "F.SilkS")
			(hide yes)
			(effects
				(font
					(size 1.27 1.27)
				)
			)
		)
		(property "Value" ""
			(at 0 0 0)
			(layer "F.Fab")
			(effects
				(font
					(size 1.27 1.27)
				)
			)
		)
		(duplicate_pad_numbers_are_jumpers no)
		(fp_line
			(start -0.7874 -0.4064)
			(end 0.7874 -0.4064)
			(stroke
				(width 0.1524)
				(type default)
			)
			(layer "F.SilkS")
		)
		(fp_line
			(start -0.7874 0.4064)
			(end -0.7874 -0.4064)
			(stroke
				(width 0.1524)
				(type default)
			)
			(layer "F.SilkS")
		)
		(fp_line
			(start 0.7874 -0.4064)
			(end 0.7874 0.4064)
			(stroke
				(width 0.1524)
				(type default)
			)
			(layer "F.SilkS")
		)
		(fp_line
			(start 0.7874 0.4064)
			(end -0.7874 0.4064)
			(stroke
				(width 0.1524)
				(type default)
			)
			(layer "F.SilkS")
		)
		(fp_line
			(start -0.67945 -0.305054)
			(end -0.12065 -0.305054)
			(stroke
				(width 0.1)
				(type default)
			)
			(layer "F.Fab")
		)
		(fp_line
			(start -0.67945 0.3048)
			(end -0.67945 -0.305054)
			(stroke
				(width 0.1)
				(type default)
			)
			(layer "F.Fab")
		)
		(fp_line
			(start -0.12065 -0.305054)
			(end -0.12065 -0.2794)
			(stroke
				(width 0.1)
				(type default)
			)
			(layer "F.Fab")
		)
		(fp_line
			(start -0.12065 -0.2794)
			(end 0.12065 -0.2794)
			(stroke
				(width 0.1)
				(type default)
			)
			(layer "F.Fab")
		)
		(fp_line
			(start -0.12065 0.2794)
			(end -0.12065 0.3048)
			(stroke
				(width 0.1)
				(type default)
			)
			(layer "F.Fab")
		)
		(fp_line
			(start -0.12065 0.3048)
			(end -0.67945 0.3048)
			(stroke
				(width 0.1)
				(type default)
			)
			(layer "F.Fab")
		)
		(fp_line
			(start 0.120396 0.2794)
			(end -0.12065 0.2794)
			(stroke
				(width 0.1)
				(type default)
			)
			(layer "F.Fab")
		)
		(fp_line
			(start 0.120396 0.3048)
			(end 0.120396 0.2794)
			(stroke
				(width 0.1)
				(type default)
			)
			(layer "F.Fab")
		)
		(fp_line
			(start 0.12065 -0.3048)
			(end 0.67945 -0.3048)
			(stroke
				(width 0.1)
				(type default)
			)
			(layer "F.Fab")
		)
		(fp_line
			(start 0.12065 -0.2794)
			(end 0.12065 -0.3048)
			(stroke
				(width 0.1)
				(type default)
			)
			(layer "F.Fab")
		)
		(fp_line
			(start 0.67945 -0.3048)
			(end 0.67945 0.3048)
			(stroke
				(width 0.1)
				(type default)
			)
			(layer "F.Fab")
		)
		(fp_line
			(start 0.67945 0.3048)
			(end 0.120396 0.3048)
			(stroke
				(width 0.1)
				(type default)
			)
			(layer "F.Fab")
		)
		(pad "1" smd circle
			(at -0.40005 0)
			(size 0 0)
			(layers "F.Cu" "F.Mask" "F.Paste")
			(net "GPU_FPGA_RST_R_N")
		)
		(pad "2" smd circle
			(at 0.40005 0)
			(size 0 0)
			(layers "F.Cu" "F.Mask" "F.Paste")
			(net "GND")
		)
	)
	(footprint ""
		(layer "F.Cu")
		(at 85.626194 -99.477322 180)
		(property "Reference" "Q99"
			(at 2.758948 0.66802 0)
			(unlocked yes)
			(layer "F.SilkS")
			(effects
				(font
					(size 0.7874 0.5842)
					(thickness 0.1524)
				)
			)
		)
		(property "Value" ""
			(at 0 0 180)
			(layer "F.Fab")
			(effects
				(font
					(size 1.27 1.27)
				)
			)
		)
		(duplicate_pad_numbers_are_jumpers no)
		(fp_line
			(start 1.376172 1.199896)
			(end -1.376172 1.199896)
			(stroke
				(width 0.1524)
				(type default)
			)
			(layer "F.SilkS")
		)
		(fp_line
			(start 1.376172 -1.199896)
			(end 1.376172 1.199896)
			(stroke
				(width 0.1524)
				(type default)
			)
			(layer "F.SilkS")
		)
		(fp_line
			(start 0.508 -1.199896)
			(end 1.376172 -1.199896)
			(stroke
				(width 0.1524)
				(type default)
			)
			(layer "F.SilkS")
		)
		(fp_line
			(start 0 -0.762)
			(end 0.508 -1.199896)
			(stroke
				(width 0.1524)
				(type default)
			)
			(layer "F.SilkS")
		)
		(fp_line
			(start -0.508 -1.199896)
			(end 0 -0.762)
			(stroke
				(width 0.1524)
				(type default)
			)
			(layer "F.SilkS")
		)
		(fp_line
			(start -1.376172 1.199896)
			(end -1.376172 -1.199896)
			(stroke
				(width 0.1524)
				(type default)
			)
			(layer "F.SilkS")
		)
		(fp_line
			(start -1.376172 -1.199896)
			(end -0.508 -1.199896)
			(stroke
				(width 0.1524)
				(type default)
			)
			(layer "F.SilkS")
		)
		(fp_poly
			(pts
				(xy -1.96596 -0.82042) (xy -2.72796 -0.43942) (xy -2.72796 -1.20142)
			)
			(stroke
				(width 0)
				(type default)
			)
			(fill yes)
			(layer "F.SilkS")
		)
		(fp_line
			(start 0.674878 1.100074)
			(end -0.674878 1.100074)
			(stroke
				(width 0.1)
				(type default)
			)
			(layer "F.Fab")
		)
		(fp_line
			(start 0.674878 -1.100074)
			(end 0.674878 1.100074)
			(stroke
				(width 0.1)
				(type default)
			)
			(layer "F.Fab")
		)
		(fp_line
			(start -0.674878 1.100074)
			(end -0.674878 -1.100074)
			(stroke
				(width 0.1)
				(type default)
			)
			(layer "F.Fab")
		)
		(fp_line
			(start -0.674878 -1.100074)
			(end 0.674878 -1.100074)
			(stroke
				(width 0.1)
				(type default)
			)
			(layer "F.Fab")
		)
		(fp_poly
			(pts
				(xy -1.4605 -0.7493) (xy -2.2225 -1.1303) (xy -2.2225 -0.3683)
			)
			(stroke
				(width 0)
				(type default)
			)
			(fill yes)
			(layer "F.Fab")
		)
		(pad "1" smd rect
			(at -0.899922 -0.750062 90)
			(size 0.6096 0.6096)
			(layers "F.Cu" "F.Mask" "F.Paste")
			(net "GND")
		)
		(pad "2" smd rect
			(at -0.899922 0 90)
			(size 0.4064 0.6096)
			(layers "F.Cu" "F.Mask" "F.Paste")
			(net "RST_PLD_CPU1_DRAM_CD_N")
		)
		(pad "3" smd rect
			(at -0.899922 0.750062 90)
			(size 0.6096 0.6096)
			(layers "F.Cu" "F.Mask" "F.Paste")
			(net "Net_1464")
		)
		(pad "4" smd rect
			(at 0.899922 0.750062 90)
			(size 0.6096 0.6096)
			(layers "F.Cu" "F.Mask" "F.Paste")
			(net "Net_1466")
		)
		(pad "5" smd rect
			(at 0.899922 0 90)
			(size 0.4064 0.6096)
			(layers "F.Cu" "F.Mask" "F.Paste")
			(net "Net_1465")
		)
		(pad "6" smd rect
			(at 0.899922 -0.750062 90)
			(size 0.6096 0.6096)
			(layers "F.Cu" "F.Mask" "F.Paste")
			(net "LED_RST_PLD_CPU1_DRAM_CD_N_D")
		)
	)
	(footprint ""
		(layer "F.Cu")
		(at 256.889504 -43.504612 180)
		(property "Reference" "PC2207"
			(at 0 0 180)
			(layer "F.SilkS")
			(hide yes)
			(effects
				(font
					(size 1.27 1.27)
				)
			)
		)
		(property "Value" ""
			(at 0 0 180)
			(layer "F.Fab")
			(effects
				(font
					(size 1.27 1.27)
				)
			)
		)
		(duplicate_pad_numbers_are_jumpers no)
		(fp_line
			(start 0.7874 0.4064)
			(end -0.7874 0.4064)
			(stroke
				(width 0.1524)
				(type default)
			)
			(layer "F.SilkS")
		)
		(fp_line
			(start 0.7874 -0.4064)
			(end 0.7874 0.4064)
			(stroke
				(width 0.1524)
				(type default)
			)
			(layer "F.SilkS")
		)
		(fp_line
			(start -0.7874 0.4064)
			(end -0.7874 -0.4064)
			(stroke
				(width 0.1524)
				(type default)
			)
			(layer "F.SilkS")
		)
		(fp_line
			(start -0.7874 -0.4064)
			(end 0.7874 -0.4064)
			(stroke
				(width 0.1524)
				(type default)
			)
			(layer "F.SilkS")
		)
		(fp_line
			(start 0.67945 0.3048)
			(end 0.120396 0.3048)
			(stroke
				(width 0.1)
				(type default)
			)
			(layer "F.Fab")
		)
		(fp_line
			(start 0.67945 -0.3048)
			(end 0.67945 0.3048)
			(stroke
				(width 0.1)
				(type default)
			)
			(layer "F.Fab")
		)
		(fp_line
			(start 0.12065 -0.2794)
			(end 0.12065 -0.3048)
			(stroke
				(width 0.1)
				(type default)
			)
			(layer "F.Fab")
		)
		(fp_line
			(start 0.12065 -0.3048)
			(end 0.67945 -0.3048)
			(stroke
				(width 0.1)
				(type default)
			)
			(layer "F.Fab")
		)
		(fp_line
			(start 0.120396 0.3048)
			(end 0.120396 0.2794)
			(stroke
				(width 0.1)
				(type default)
			)
			(layer "F.Fab")
		)
		(fp_line
			(start 0.120396 0.2794)
			(end -0.12065 0.2794)
			(stroke
				(width 0.1)
				(type default)
			)
			(layer "F.Fab")
		)
		(fp_line
			(start -0.12065 0.3048)
			(end -0.67945 0.3048)
			(stroke
				(width 0.1)
				(type default)
			)
			(layer "F.Fab")
		)
		(fp_line
			(start -0.12065 0.2794)
			(end -0.12065 0.3048)
			(stroke
				(width 0.1)
				(type default)
			)
			(layer "F.Fab")
		)
		(fp_line
			(start -0.12065 -0.2794)
			(end 0.12065 -0.2794)
			(stroke
				(width 0.1)
				(type default)
			)
			(layer "F.Fab")
		)
		(fp_line
			(start -0.12065 -0.305054)
			(end -0.12065 -0.2794)
			(stroke
				(width 0.1)
				(type default)
			)
			(layer "F.Fab")
		)
		(fp_line
			(start -0.67945 0.3048)
			(end -0.67945 -0.305054)
			(stroke
				(width 0.1)
				(type default)
			)
			(layer "F.Fab")
		)
		(fp_line
			(start -0.67945 -0.305054)
			(end -0.12065 -0.305054)
			(stroke
				(width 0.1)
				(type default)
			)
			(layer "F.Fab")
		)
		(pad "1" smd circle
			(at -0.40005 0 180)
			(size 0 0)
			(layers "F.Cu" "F.Mask" "F.Paste")
			(net "P12V_AUX")
		)
		(pad "2" smd circle
			(at 0.40005 0 180)
			(size 0 0)
			(layers "F.Cu" "F.Mask" "F.Paste")
			(net "GND")
		)
	)
)
